(kicad_pcb
	(version 20260206)
	(generator "pcbnew")
	(generator_version "10.0")
	(general
		(thickness 1.6)
		(legacy_teardrops no)
	)
	(paper "A4")
	(title_block
		(title "Wiwynn_Tioga_Pass_MB.brd")
		(comment 1 "Tioga Pass / footprints 1287-1291 of 4770")
	)
	(layers
		(0 "F.Cu" signal "TOP")
		(4 "In1.Cu" signal "L2GND")
		(6 "In2.Cu" signal "L3")
		(8 "In3.Cu" signal "L4GND")
		(10 "In4.Cu" signal "L5")
		(12 "In5.Cu" signal "L6GND")
		(14 "In6.Cu" signal "L7VCC")
		(16 "In7.Cu" signal "L8VCC")
		(18 "In8.Cu" signal "L9GND")
		(20 "In9.Cu" signal "L10")
		(22 "In10.Cu" signal "L11GND")
		(24 "In11.Cu" signal "L12")
		(26 "In12.Cu" signal "L13GND")
		(2 "B.Cu" signal "BOTTOM")
		(9 "F.Adhes" user "F.Adhesive")
		(11 "B.Adhes" user "B.Adhesive")
		(13 "F.Paste" user "Package Geometry/Pastemask Top")
		(15 "B.Paste" user "Package Geometry/Pastemask Bottom")
		(5 "F.SilkS" user "Ref Des/Silkscreen Top")
		(7 "B.SilkS" user "Ref Des/Silkscreen Bottom")
		(1 "F.Mask" user "Board Geometry/Soldermask Top")
		(3 "B.Mask" user "Board Geometry/Soldermask Bottom")
		(17 "Dwgs.User" user "User.Drawings")
		(19 "Cmts.User" user "User.Comments")
		(21 "Eco1.User" user "User.Eco1")
		(23 "Eco2.User" user "User.Eco2")
		(25 "Edge.Cuts" user "Board Geometry/Outline")
		(27 "Margin" user)
		(31 "F.CrtYd" user "Package Geometry/Place Bound Top")
		(29 "B.CrtYd" user "Package Geometry/Place Bound Bottom")
		(35 "F.Fab" user "Ref Des/Assembly Top")
		(33 "B.Fab" user "Ref Des/Assembly Bottom")
	)
	(footprint ""
		(layer "F.Cu")
		(at 192.62725 -90.3859 90)
		(property "Reference" "RT23"
			(at 1.01473 0.656336 0)
			(unlocked yes)
			(layer "F.SilkS")
			(effects
				(font
					(size 0.4064 0.254)
					(thickness 0.1524)
				)
			)
		)
		(property "Value" ""
			(at 0 0 90)
			(layer "F.Fab")
			(effects
				(font
					(size 1.27 1.27)
				)
			)
		)
		(duplicate_pad_numbers_are_jumpers no)
		(fp_poly
			(pts
				(xy -0.4953 -0.2032) (xy 0.4953 -0.2032) (xy 0.4953 1.6002) (xy -0.4953 1.6002)
			)
			(stroke
				(width 0)
				(type default)
			)
			(fill no)
			(layer "F.CrtYd")
		)
		(fp_line
			(start 0.4953 -0.2032)
			(end 0.4953 1.6002)
			(stroke
				(width 0.1)
				(type default)
			)
			(layer "F.Fab")
		)
		(fp_line
			(start -0.4953 -0.2032)
			(end 0.4953 -0.2032)
			(stroke
				(width 0.1)
				(type default)
			)
			(layer "F.Fab")
		)
		(fp_line
			(start 0.4953 1.6002)
			(end -0.4953 1.6002)
			(stroke
				(width 0.1)
				(type default)
			)
			(layer "F.Fab")
		)
		(fp_line
			(start -0.4953 1.6002)
			(end -0.4953 -0.2032)
			(stroke
				(width 0.1)
				(type default)
			)
			(layer "F.Fab")
		)
		(pad "1" smd rect
			(at 0 0 90)
			(size 0.762 0.889)
			(layers "F.Cu" "F.Mask" "F.Paste")
			(net "VR_PVCCIN_CPU0_PH5_BOOT")
		)
		(pad "2" smd rect
			(at 0 1.397 90)
			(size 0.762 0.889)
			(layers "F.Cu" "F.Mask" "F.Paste")
			(net "VR_PVCCIN_CPU0_PH5_BOOT_R")
		)
		(zone
			(layer "F.Cu")
			(hatch none 0.5)
			(connect_pads
				(clearance 0)
			)
			(min_thickness 0.25)
			(keepout
				(tracks allowed)
				(vias not_allowed)
				(pads allowed)
				(copperpour not_allowed)
				(footprints allowed)
			)
			(placement
				(enabled no)
				(sheetname "")
			)
			(fill
				(thermal_gap 0.5)
				(thermal_bridge_width 0.5)
				(island_removal_mode 0)
			)
			(polygon
				(pts
					(xy 193.57975 -90.7669) (xy 193.07175 -90.7669) (xy 193.07175 -90.0049) (xy 193.57975 -90.0049)
				)
			)
		)
		(zone
			(layer "F.Cu")
			(hatch none 0.5)
			(connect_pads
				(clearance 0)
			)
			(min_thickness 0.25)
			(keepout
				(tracks not_allowed)
				(vias allowed)
				(pads allowed)
				(copperpour not_allowed)
				(footprints allowed)
			)
			(placement
				(enabled no)
				(sheetname "")
			)
			(fill
				(thermal_gap 0.5)
				(thermal_bridge_width 0.5)
				(island_removal_mode 0)
			)
			(polygon
				(pts
					(xy 193.57975 -90.0049) (xy 193.57975 -90.7669) (xy 193.07175 -90.7669) (xy 193.07175 -90.0049)
				)
			)
		)
	)
	(footprint ""
		(layer "F.Cu")
		(at 399.758916 -35.041586 -90)
		(property "Reference" "R8G5"
			(at 0 0 270)
			(layer "F.SilkS")
			(hide yes)
			(effects
				(font
					(size 1.27 1.27)
				)
			)
		)
		(property "Value" ""
			(at 0 0 270)
			(layer "F.Fab")
			(effects
				(font
					(size 1.27 1.27)
				)
			)
		)
		(duplicate_pad_numbers_are_jumpers no)
		(fp_poly
			(pts
				(xy -0.2794 -0.1016) (xy 0.2794 -0.1016) (xy 0.2794 0.9906) (xy -0.2794 0.9906)
			)
			(stroke
				(width 0)
				(type default)
			)
			(fill no)
			(layer "F.CrtYd")
		)
		(fp_line
			(start -0.2794 0.9906)
			(end 0.2794 0.9906)
			(stroke
				(width 0.1)
				(type default)
			)
			(layer "F.Fab")
		)
		(fp_line
			(start 0.2794 0.9906)
			(end 0.2794 -0.1016)
			(stroke
				(width 0.1)
				(type default)
			)
			(layer "F.Fab")
		)
		(fp_line
			(start -0.2794 -0.1016)
			(end -0.2794 0.9906)
			(stroke
				(width 0.1)
				(type default)
			)
			(layer "F.Fab")
		)
		(fp_line
			(start 0.2794 -0.1016)
			(end -0.2794 -0.1016)
			(stroke
				(width 0.1)
				(type default)
			)
			(layer "F.Fab")
		)
		(pad "1" smd rect
			(at 0 0 270)
			(size 0.508 0.508)
			(layers "F.Cu" "F.Mask" "F.Paste")
			(net "SMB_OCP_LAN_STBY_LVC3_SDA_R")
		)
		(pad "2" smd rect
			(at 0 0.889 270)
			(size 0.508 0.508)
			(layers "F.Cu" "F.Mask" "F.Paste")
			(net "SMB_OCP_LAN_STBY_LVC3_SDA")
		)
		(zone
			(layer "F.Cu")
			(hatch none 0.5)
			(connect_pads
				(clearance 0)
			)
			(min_thickness 0.25)
			(keepout
				(tracks not_allowed)
				(vias allowed)
				(pads allowed)
				(copperpour not_allowed)
				(footprints allowed)
			)
			(placement
				(enabled no)
				(sheetname "")
			)
			(fill
				(thermal_gap 0.5)
				(thermal_bridge_width 0.5)
				(island_removal_mode 0)
			)
			(polygon
				(pts
					(xy 399.123916 -35.295586) (xy 399.123916 -34.787586) (xy 399.504916 -34.787586) (xy 399.504916 -35.295586)
				)
			)
		)
		(zone
			(layer "F.Cu")
			(hatch none 0.5)
			(connect_pads
				(clearance 0)
			)
			(min_thickness 0.25)
			(keepout
				(tracks allowed)
				(vias not_allowed)
				(pads allowed)
				(copperpour not_allowed)
				(footprints allowed)
			)
			(placement
				(enabled no)
				(sheetname "")
			)
			(fill
				(thermal_gap 0.5)
				(thermal_bridge_width 0.5)
				(island_removal_mode 0)
			)
			(polygon
				(pts
					(xy 399.504916 -35.295586) (xy 399.504916 -34.787586) (xy 399.123916 -34.787586) (xy 399.123916 -35.295586)
				)
			)
		)
	)
	(footprint ""
		(layer "F.Cu")
		(at 36.7538 -69.3166 -90)
		(property "Reference" "RT12"
			(at 0 0 270)
			(layer "F.SilkS")
			(hide yes)
			(effects
				(font
					(size 1.27 1.27)
				)
			)
		)
		(property "Value" "*"
			(at -0.0254 -2.6289 270)
			(unlocked yes)
			(layer "F.Fab")
			(hide yes)
			(effects
				(font
					(size 1.27 1.016)
					(thickness 0.1524)
				)
			)
		)
		(property "Device Type" "1R3F-GP_RCL_GP-1R3F-GP,64.1R00A"
			(at -0.0254 -4.1529 270)
			(unlocked yes)
			(layer "F.Fab")
			(hide yes)
			(effects
				(font
					(size 1.27 1.016)
					(thickness 0.1524)
				)
			)
		)
		(duplicate_pad_numbers_are_jumpers no)
		(fp_line
			(start -0.4826 0)
			(end -0.2032 0)
			(stroke
				(width 0.2032)
				(type default)
			)
			(layer "F.SilkS")
		)
		(fp_line
			(start 0.2032 0)
			(end 0.4826 0)
			(stroke
				(width 0.2032)
				(type default)
			)
			(layer "F.SilkS")
		)
		(fp_rect
			(start -0.5842 1.3335)
			(end 0.5842 -1.3335)
			(stroke
				(width 0)
				(type default)
			)
			(fill no)
			(layer "F.CrtYd")
		)
		(fp_rect
			(start -0.5842 1.3335)
			(end 0.5842 -1.3335)
			(stroke
				(width 0)
				(type default)
			)
			(fill no)
			(layer "F.Fab")
		)
		(pad "1" smd custom
			(at 0 -0.762 270)
			(size 0.2159 0.2159)
			(layers "F.Cu" "F.Mask" "F.Paste")
			(net "VR_PVCCIN_CPU1_PHASE3_RC")
			(options
				(clearance outline)
				(anchor circle)
			)
			(primitives
				(gr_poly
					(pts
						(arc
							(start -0.3302 -0.4318)
							(mid -0.402042 -0.402042)
							(end -0.4318 -0.3302)
						)
						(arc
							(start -0.4318 0.3302)
							(mid -0.402042 0.402042)
							(end -0.3302 0.4318)
						)
						(arc
							(start 0.3302 0.4318)
							(mid 0.402042 0.402042)
							(end 0.4318 0.3302)
						)
						(arc
							(start 0.4318 -0.3302)
							(mid 0.402042 -0.402042)
							(end 0.3302 -0.4318)
						)
					)
					(width 0)
					(fill yes)
				)
			)
		)
		(pad "2" smd custom
			(at 0 0.762 270)
			(size 0.2159 0.2159)
			(layers "F.Cu" "F.Mask" "F.Paste")
			(net "GND")
			(options
				(clearance outline)
				(anchor circle)
			)
			(primitives
				(gr_poly
					(pts
						(arc
							(start -0.3302 -0.4318)
							(mid -0.402042 -0.402042)
							(end -0.4318 -0.3302)
						)
						(arc
							(start -0.4318 0.3302)
							(mid -0.402042 0.402042)
							(end -0.3302 0.4318)
						)
						(arc
							(start 0.3302 0.4318)
							(mid 0.402042 0.402042)
							(end 0.4318 0.3302)
						)
						(arc
							(start 0.4318 -0.3302)
							(mid 0.402042 -0.402042)
							(end 0.3302 -0.4318)
						)
					)
					(width 0)
					(fill yes)
				)
			)
		)
	)
	(footprint ""
		(layer "F.Cu")
		(at 340.7664 -128.3335)
		(property "Reference" "R7B13"
			(at 0 0 0)
			(layer "F.SilkS")
			(hide yes)
			(effects
				(font
					(size 1.27 1.27)
				)
			)
		)
		(property "Value" ""
			(at 0 0 0)
			(layer "F.Fab")
			(effects
				(font
					(size 1.27 1.27)
				)
			)
		)
		(duplicate_pad_numbers_are_jumpers no)
		(fp_poly
			(pts
				(xy -0.2794 -0.1016) (xy 0.2794 -0.1016) (xy 0.2794 0.9906) (xy -0.2794 0.9906)
			)
			(stroke
				(width 0)
				(type default)
			)
			(fill no)
			(layer "F.CrtYd")
		)
		(fp_line
			(start -0.2794 -0.1016)
			(end -0.2794 0.9906)
			(stroke
				(width 0.1)
				(type default)
			)
			(layer "F.Fab")
		)
		(fp_line
			(start -0.2794 0.9906)
			(end 0.2794 0.9906)
			(stroke
				(width 0.1)
				(type default)
			)
			(layer "F.Fab")
		)
		(fp_line
			(start 0.2794 -0.1016)
			(end -0.2794 -0.1016)
			(stroke
				(width 0.1)
				(type default)
			)
			(layer "F.Fab")
		)
		(fp_line
			(start 0.2794 0.9906)
			(end 0.2794 -0.1016)
			(stroke
				(width 0.1)
				(type default)
			)
			(layer "F.Fab")
		)
		(pad "1" smd rect
			(at 0 0)
			(size 0.508 0.508)
			(layers "F.Cu" "F.Mask" "F.Paste")
			(net "VR_FB_PVPP_DEF")
		)
		(pad "2" smd rect
			(at 0 0.889)
			(size 0.508 0.508)
			(layers "F.Cu" "F.Mask" "F.Paste")
			(net "AGND_PVPP_DEF")
		)
		(zone
			(layer "F.Cu")
			(hatch none 0.5)
			(connect_pads
				(clearance 0)
			)
			(min_thickness 0.25)
			(keepout
				(tracks allowed)
				(vias not_allowed)
				(pads allowed)
				(copperpour not_allowed)
				(footprints allowed)
			)
			(placement
				(enabled no)
				(sheetname "")
			)
			(fill
				(thermal_gap 0.5)
				(thermal_bridge_width 0.5)
				(island_removal_mode 0)
			)
			(polygon
				(pts
					(xy 340.5124 -128.0795) (xy 341.0204 -128.0795) (xy 341.0204 -127.6985) (xy 340.5124 -127.6985)
				)
			)
		)
		(zone
			(layer "F.Cu")
			(hatch none 0.5)
			(connect_pads
				(clearance 0)
			)
			(min_thickness 0.25)
			(keepout
				(tracks not_allowed)
				(vias allowed)
				(pads allowed)
				(copperpour not_allowed)
				(footprints allowed)
			)
			(placement
				(enabled no)
				(sheetname "")
			)
			(fill
				(thermal_gap 0.5)
				(thermal_bridge_width 0.5)
				(island_removal_mode 0)
			)
			(polygon
				(pts
					(xy 340.5124 -127.6985) (xy 341.0204 -127.6985) (xy 341.0204 -128.0795) (xy 340.5124 -128.0795)
				)
			)
		)
	)
	(footprint ""
		(layer "F.Cu")
		(at 318.8716 -28.045918 180)
		(property "Reference" "R6F8"
			(at 0 0 180)
			(layer "F.SilkS")
			(hide yes)
			(effects
				(font
					(size 1.27 1.27)
				)
			)
		)
		(property "Value" ""
			(at 0 0 180)
			(layer "F.Fab")
			(effects
				(font
					(size 1.27 1.27)
				)
			)
		)
		(duplicate_pad_numbers_are_jumpers no)
		(fp_poly
			(pts
				(xy -0.2794 -0.1016) (xy 0.2794 -0.1016) (xy 0.2794 0.9906) (xy -0.2794 0.9906)
			)
			(stroke
				(width 0)
				(type default)
			)
			(fill no)
			(layer "F.CrtYd")
		)
		(fp_line
			(start 0.2794 0.9906)
			(end 0.2794 -0.1016)
			(stroke
				(width 0.1)
				(type default)
			)
			(layer "F.Fab")
		)
		(fp_line
			(start 0.2794 -0.1016)
			(end -0.2794 -0.1016)
			(stroke
				(width 0.1)
				(type default)
			)
			(layer "F.Fab")
		)
		(fp_line
			(start -0.2794 0.9906)
			(end 0.2794 0.9906)
			(stroke
				(width 0.1)
				(type default)
			)
			(layer "F.Fab")
		)
		(fp_line
			(start -0.2794 -0.1016)
			(end -0.2794 0.9906)
			(stroke
				(width 0.1)
				(type default)
			)
			(layer "F.Fab")
		)
		(pad "1" smd rect
			(at 0 0 180)
			(size 0.508 0.508)
			(layers "F.Cu" "F.Mask" "F.Paste")
			(net "CLK_322M_156M_CPU0_OSC_VRM_DP")
		)
		(pad "2" smd rect
			(at 0 0.889 180)
			(size 0.508 0.508)
			(layers "F.Cu" "F.Mask" "F.Paste")
			(net "CLK_156M_OSC_CPU0_HFI_DP")
		)
		(zone
			(layer "F.Cu")
			(hatch none 0.5)
			(connect_pads
				(clearance 0)
			)
			(min_thickness 0.25)
			(keepout
				(tracks not_allowed)
				(vias allowed)
				(pads allowed)
				(copperpour not_allowed)
				(footprints allowed)
			)
			(placement
				(enabled no)
				(sheetname "")
			)
			(fill
				(thermal_gap 0.5)
				(thermal_bridge_width 0.5)
				(island_removal_mode 0)
			)
			(polygon
				(pts
					(xy 319.1256 -28.680918) (xy 318.6176 -28.680918) (xy 318.6176 -28.299918) (xy 319.1256 -28.299918)
				)
			)
		)
		(zone
			(layer "F.Cu")
			(hatch none 0.5)
			(connect_pads
				(clearance 0)
			)
			(min_thickness 0.25)
			(keepout
				(tracks allowed)
				(vias not_allowed)
				(pads allowed)
				(copperpour not_allowed)
				(footprints allowed)
			)
			(placement
				(enabled no)
				(sheetname "")
			)
			(fill
				(thermal_gap 0.5)
				(thermal_bridge_width 0.5)
				(island_removal_mode 0)
			)
			(polygon
				(pts
					(xy 319.1256 -28.299918) (xy 318.6176 -28.299918) (xy 318.6176 -28.680918) (xy 319.1256 -28.680918)
				)
			)
		)
	)
)
